(kicad_pcb
	(version 20260206)
	(generator "pcbnew")
	(generator_version "10.0")
	(general
		(thickness 1.21888)
		(legacy_teardrops no)
	)
	(paper "A4")
	(title_block
		(title "timecard-v8 — TimeCard-DC-V8_EXP.PcbDoc")
		(comment 1 "Time Appliance Project (Time Card) / footprints 133-143 of 288")
	)
	(layers
		(0 "F.Cu" signal "TOP")
		(4 "In1.Cu" signal "SGND")
		(6 "In2.Cu" signal "IN1")
		(8 "In3.Cu" signal "IN2")
		(10 "In4.Cu" signal "SGND1")
		(2 "B.Cu" signal "BOTTOM")
		(9 "F.Adhes" user "F.Adhesive")
		(11 "B.Adhes" user "B.Adhesive")
		(13 "F.Paste" user "Top Paste")
		(15 "B.Paste" user "Bottom Paste")
		(5 "F.SilkS" user "Top Overlay")
		(7 "B.SilkS" user "Bottom Overlay")
		(1 "F.Mask" user "Top Solder")
		(3 "B.Mask" user "Bottom Solder")
		(17 "Dwgs.User" user "User.Drawings")
		(19 "Cmts.User" user "User.Comments")
		(21 "Eco1.User" user "User.Eco1")
		(23 "Eco2.User" user "User.Eco2")
		(25 "Edge.Cuts" user)
		(27 "Margin" user)
		(31 "F.CrtYd" user "Top Courtyard")
		(29 "B.CrtYd" user "Bottom Courtyard")
		(35 "F.Fab" user "Top Component Center")
		(33 "B.Fab" user "Bottom Component Center")
	)
	(footprint "SamacSys:155124M173200"
		(layer "F.Cu")
		(at 58.4511 128.4162 90)
		(property "Reference" "D17"
			(at -0.4714 1.701931 90)
			(unlocked yes)
			(layer "F.SilkS")
			(effects
				(font
					(size 0.762 0.762)
					(thickness 0.2286)
				)
			)
		)
		(property "Value" "155124M173200"
			(at 7.1471 2.605271 90)
			(unlocked yes)
			(layer "F.SilkS")
			(hide yes)
			(effects
				(font
					(size 0.762 0.762)
					(thickness 0.2286)
				)
			)
		)
		(sheetname "USER_IO_STATUS")
		(sheetfile "USER_IO_STATUS.kicad_sch")
		(duplicate_pad_numbers_are_jumpers no)
		(fp_line
			(start -0.8 0.5)
			(end 0.8 0.5)
			(stroke
				(width 0.1)
				(type solid)
			)
			(layer "F.SilkS")
		)
		(fp_arc
			(start -2 -0.1)
			(mid -1.95 -0.05)
			(end -2 0)
			(stroke
				(width 0.1)
				(type solid)
			)
			(layer "F.SilkS")
		)
		(fp_arc
			(start -2 0)
			(mid -2.05 -0.05)
			(end -2 -0.1)
			(stroke
				(width 0.1)
				(type solid)
			)
			(layer "F.SilkS")
		)
		(pad "1" smd rect
			(at -1.4 0 180)
			(size 0.9 0.6)
			(layers "F.Cu" "F.Mask" "F.Paste")
			(net "+3.3V")
		)
		(pad "2" smd rect
			(at -0.45 -0.325 90)
			(size 0.6 0.55)
			(layers "F.Cu" "F.Mask" "F.Paste")
			(net "NetD17_2")
		)
		(pad "3" smd rect
			(at 0.45 -0.325 90)
			(size 0.6 0.55)
			(layers "F.Cu" "F.Mask" "F.Paste")
			(net "NetD17_3")
		)
		(pad "4" smd rect
			(at 1.4 0 180)
			(size 0.9 0.6)
			(layers "F.Cu" "F.Mask" "F.Paste")
			(net "NetD17_4")
		)
	)
	(footprint "Vault:FP-C1005-050-0_05-IPC_A"
		(layer "F.Cu")
		(at 232.5261 107.8162 -90)
		(property "Reference" "C16"
			(at 1.3 1.106655 90)
			(unlocked yes)
			(layer "F.SilkS")
			(effects
				(font
					(size 0.762 0.762)
					(thickness 0.2286)
				)
				(justify left bottom)
			)
		)
		(property "Value" "2.2uF_16V_0402"
			(at 2.993045 -13.2355 0)
			(unlocked yes)
			(layer "F.SilkS")
			(hide yes)
			(effects
				(font
					(size 0.762 0.762)
					(thickness 0.2286)
				)
				(justify left bottom)
			)
		)
		(sheetname "POWER")
		(sheetfile "POWER.kicad_sch")
		(duplicate_pad_numbers_are_jumpers no)
		(fp_line
			(start 0.83624 0.73624)
			(end -0.83624 0.73624)
			(stroke
				(width 0.2)
				(type solid)
			)
			(layer "F.SilkS")
		)
		(fp_line
			(start 0.83624 -0.73624)
			(end -0.83624 -0.73624)
			(stroke
				(width 0.2)
				(type solid)
			)
			(layer "F.SilkS")
		)
		(fp_line
			(start -1.03624 0.53624)
			(end -1.03624 -0.53624)
			(stroke
				(width 0.2)
				(type solid)
			)
			(layer "F.CrtYd")
		)
		(fp_line
			(start 1.03624 0.53624)
			(end -1.03624 0.53624)
			(stroke
				(width 0.2)
				(type solid)
			)
			(layer "F.CrtYd")
		)
		(fp_line
			(start 1.03624 0.53624)
			(end 1.03624 -0.53624)
			(stroke
				(width 0.2)
				(type solid)
			)
			(layer "F.CrtYd")
		)
		(fp_line
			(start 1.03624 -0.53624)
			(end -1.03624 -0.53624)
			(stroke
				(width 0.2)
				(type solid)
			)
			(layer "F.CrtYd")
		)
		(fp_line
			(start -1.03624 0.53624)
			(end -1.03624 -0.53624)
			(stroke
				(width 0.2)
				(type solid)
			)
			(layer "F.Fab")
		)
		(fp_line
			(start 1.03624 0.53624)
			(end -1.03624 0.53624)
			(stroke
				(width 0.2)
				(type solid)
			)
			(layer "F.Fab")
		)
		(fp_line
			(start 1.03624 0.53624)
			(end 1.03624 -0.53624)
			(stroke
				(width 0.2)
				(type solid)
			)
			(layer "F.Fab")
		)
		(fp_line
			(start 0 0.5)
			(end 0 -0.5)
			(stroke
				(width 0.1)
				(type solid)
			)
			(layer "F.Fab")
		)
		(fp_line
			(start 0.5 0)
			(end -0.5 0)
			(stroke
				(width 0.1)
				(type solid)
			)
			(layer "F.Fab")
		)
		(fp_line
			(start 1.03624 -0.53624)
			(end -1.03624 -0.53624)
			(stroke
				(width 0.2)
				(type solid)
			)
			(layer "F.Fab")
		)
		(fp_text user "${REFERENCE}"
			(at -0.00001 0.09602 270)
			(unlocked yes)
			(layer "F.Fab")
			(effects
				(font
					(face "Arial")
					(size 0.63 0.63)
					(thickness 0.1)
				)
				(justify left bottom)
			)
		)
		(pad "1" smd rect
			(at -0.46657 0 270)
			(size 0.73933 0.67248)
			(layers "F.Cu" "F.Mask" "F.Paste")
			(net "+5.0V")
			(solder_mask_margin 0)
			(solder_paste_margin 0)
		)
		(pad "2" smd rect
			(at 0.46658 0 270)
			(size 0.73933 0.67248)
			(layers "F.Cu" "F.Mask" "F.Paste")
			(net "GND")
			(solder_mask_margin 0)
			(solder_paste_margin 0)
		)
	)
	(footprint "Vault:FP-0402-L_1_0_1-W_0_5_0_1-IPC_C"
		(layer "F.Cu")
		(at 206.0261 109.6162 90)
		(property "Reference" "C6"
			(at -4.1 0.593345 90)
			(unlocked yes)
			(layer "F.SilkS")
			(effects
				(font
					(size 0.762 0.762)
					(thickness 0.2286)
				)
				(justify left bottom)
			)
		)
		(property "Value" "0.1uF_25V_0402"
			(at -5.449845 12.8601 0)
			(unlocked yes)
			(layer "F.SilkS")
			(hide yes)
			(effects
				(font
					(size 0.762 0.762)
					(thickness 0.2286)
				)
				(justify left bottom)
			)
		)
		(sheetname "POWER")
		(sheetfile "POWER.kicad_sch")
		(duplicate_pad_numbers_are_jumpers no)
		(fp_line
			(start -0.65607 -0.7)
			(end 0.65607 -0.7)
			(stroke
				(width 0.2)
				(type solid)
			)
			(layer "F.SilkS")
		)
		(fp_line
			(start -0.65607 0.7)
			(end 0.65607 0.7)
			(stroke
				(width 0.2)
				(type solid)
			)
			(layer "F.SilkS")
		)
		(fp_line
			(start 0.75607 -0.4)
			(end 0.75607 0.4)
			(stroke
				(width 0.2)
				(type solid)
			)
			(layer "F.CrtYd")
		)
		(fp_line
			(start -0.75607 -0.4)
			(end 0.75607 -0.4)
			(stroke
				(width 0.2)
				(type solid)
			)
			(layer "F.CrtYd")
		)
		(fp_line
			(start -0.75607 -0.4)
			(end -0.75607 0.4)
			(stroke
				(width 0.2)
				(type solid)
			)
			(layer "F.CrtYd")
		)
		(fp_line
			(start -0.75607 0.4)
			(end 0.75607 0.4)
			(stroke
				(width 0.2)
				(type solid)
			)
			(layer "F.CrtYd")
		)
		(fp_line
			(start 0 -0.5)
			(end 0 0.5)
			(stroke
				(width 0.1)
				(type solid)
			)
			(layer "F.Fab")
		)
		(fp_line
			(start 0.75607 -0.4)
			(end 0.75607 0.4)
			(stroke
				(width 0.2)
				(type solid)
			)
			(layer "F.Fab")
		)
		(fp_line
			(start -0.75607 -0.4)
			(end 0.75607 -0.4)
			(stroke
				(width 0.2)
				(type solid)
			)
			(layer "F.Fab")
		)
		(fp_line
			(start -0.75607 -0.4)
			(end -0.75607 0.4)
			(stroke
				(width 0.2)
				(type solid)
			)
			(layer "F.Fab")
		)
		(fp_line
			(start -0.5 0)
			(end 0.5 0)
			(stroke
				(width 0.1)
				(type solid)
			)
			(layer "F.Fab")
		)
		(fp_line
			(start -0.75607 0.4)
			(end 0.75607 0.4)
			(stroke
				(width 0.2)
				(type solid)
			)
			(layer "F.Fab")
		)
		(fp_text user "${REFERENCE}"
			(at -0.00001 0.09602 90)
			(unlocked yes)
			(layer "F.Fab")
			(effects
				(font
					(face "Arial")
					(size 0.63 0.63)
					(thickness 0.1)
				)
				(justify left bottom)
			)
		)
		(pad "1" smd rect
			(at -0.36554 0 90)
			(size 0.58106 0.51213)
			(layers "F.Cu" "F.Mask" "F.Paste")
			(net "NetC6_1")
			(solder_mask_margin 0)
			(solder_paste_margin 0)
		)
		(pad "2" smd rect
			(at 0.36554 0 90)
			(size 0.58106 0.51213)
			(layers "F.Cu" "F.Mask" "F.Paste")
			(net "GND")
			(solder_mask_margin 0)
			(solder_paste_margin 0)
		)
	)
	(footprint "Capacitors:CAPC2012X14N"
		(layer "F.Cu")
		(at 209.8261 85.8162 90)
		(property "Reference" "C1"
			(at 1.9 0.393345 90)
			(unlocked yes)
			(layer "F.SilkS")
			(effects
				(font
					(size 0.762 0.762)
					(thickness 0.2286)
				)
				(justify left bottom)
			)
		)
		(property "Value" "CAP_0805_10UF_25V"
			(at -3.433445 -1.5875 0)
			(unlocked yes)
			(layer "F.SilkS")
			(hide yes)
			(effects
				(font
					(size 0.762 0.762)
					(thickness 0.2286)
				)
				(justify left bottom)
			)
		)
		(sheetname "POWER")
		(sheetfile "POWER.kicad_sch")
		(duplicate_pad_numbers_are_jumpers no)
		(fp_line
			(start -0.762 -0.9652)
			(end 0.762 -0.9652)
			(stroke
				(width 0.1524)
				(type solid)
			)
			(layer "F.SilkS")
		)
		(fp_line
			(start -0.762 0.9652)
			(end 0.762 0.9652)
			(stroke
				(width 0.1524)
				(type solid)
			)
			(layer "F.SilkS")
		)
		(pad "1" smd rect
			(at -0.9 0 180)
			(size 1.45 1.15)
			(layers "F.Cu" "F.Mask" "F.Paste")
			(net "+12V")
		)
		(pad "2" smd rect
			(at 0.9 0 180)
			(size 1.45 1.15)
			(layers "F.Cu" "F.Mask" "F.Paste")
			(net "GND")
		)
	)
	(footprint "Vault:FP-MK212BG-MFG"
		(layer "F.Cu")
		(at 232.7261 69.5162)
		(property "Reference" "C56"
			(at 0.9286 1.726931 0)
			(unlocked yes)
			(layer "F.SilkS")
			(effects
				(font
					(size 0.762 0.762)
					(thickness 0.2286)
				)
			)
		)
		(property "Value" "10uF"
			(at -3.240271 2.22164 270)
			(unlocked yes)
			(layer "F.SilkS")
			(hide yes)
			(effects
				(font
					(size 0.762 0.762)
					(thickness 0.2286)
				)
			)
		)
		(sheetname "GPS_IMU_SENSORS")
		(sheetfile "GPS_IMU_SENSORS.kicad_sch")
		(duplicate_pad_numbers_are_jumpers no)
		(fp_line
			(start -0.125 -0.725)
			(end 0.125 -0.725)
			(stroke
				(width 0.2)
				(type solid)
			)
			(layer "F.SilkS")
		)
		(fp_line
			(start -0.125 0.725)
			(end 0.125 0.725)
			(stroke
				(width 0.2)
				(type solid)
			)
			(layer "F.SilkS")
		)
		(fp_line
			(start -1.6 -0.825)
			(end 1.6 -0.825)
			(stroke
				(width 0.2)
				(type solid)
			)
			(layer "F.CrtYd")
		)
		(fp_line
			(start -1.6 0.825)
			(end -1.6 -0.825)
			(stroke
				(width 0.2)
				(type solid)
			)
			(layer "F.CrtYd")
		)
		(fp_line
			(start -1.6 0.825)
			(end 1.6 0.825)
			(stroke
				(width 0.2)
				(type solid)
			)
			(layer "F.CrtYd")
		)
		(fp_line
			(start 1.6 0.825)
			(end 1.6 -0.825)
			(stroke
				(width 0.2)
				(type solid)
			)
			(layer "F.CrtYd")
		)
		(fp_line
			(start -1.6 -0.825)
			(end 1.6 -0.825)
			(stroke
				(width 0.2)
				(type solid)
			)
			(layer "F.Fab")
		)
		(fp_line
			(start -1.6 0.825)
			(end -1.6 -0.825)
			(stroke
				(width 0.2)
				(type solid)
			)
			(layer "F.Fab")
		)
		(fp_line
			(start -1.6 0.825)
			(end 1.6 0.825)
			(stroke
				(width 0.2)
				(type solid)
			)
			(layer "F.Fab")
		)
		(fp_line
			(start -0.5 0)
			(end 0.5 0)
			(stroke
				(width 0.1)
				(type solid)
			)
			(layer "F.Fab")
		)
		(fp_line
			(start 0 0.5)
			(end 0 -0.5)
			(stroke
				(width 0.1)
				(type solid)
			)
			(layer "F.Fab")
		)
		(fp_line
			(start 1.6 0.825)
			(end 1.6 -0.825)
			(stroke
				(width 0.2)
				(type solid)
			)
			(layer "F.Fab")
		)
		(fp_text user "${REFERENCE}"
			(at -0.00001 0.09602 360)
			(unlocked yes)
			(layer "F.Fab")
			(effects
				(font
					(face "Arial")
					(size 0.63 0.63)
					(thickness 0.1)
				)
				(justify left bottom)
			)
		)
		(pad "1" smd rect
			(at -1 0)
			(size 1 1.25)
			(layers "F.Cu" "F.Mask" "F.Paste")
			(net "+5.0V")
			(solder_mask_margin 0)
			(solder_paste_margin 0)
		)
		(pad "2" smd rect
			(at 1 0)
			(size 1 1.25)
			(layers "F.Cu" "F.Mask" "F.Paste")
			(net "GND")
			(solder_mask_margin 0)
			(solder_paste_margin 0)
		)
	)
	(footprint "Vault:RESC1608X55X30NL15T15"
		(layer "F.Cu")
		(at 82.1261 98.8662 -90)
		(property "Reference" "R15"
			(at 2.7714 -0.026921 90)
			(unlocked yes)
			(layer "F.SilkS")
			(effects
				(font
					(size 0.762 0.762)
					(thickness 0.2286)
				)
			)
		)
		(property "Value" "4.7K"
			(at 2.808471 -4.96406 0)
			(unlocked yes)
			(layer "F.SilkS")
			(hide yes)
			(effects
				(font
					(size 0.762 0.762)
					(thickness 0.2286)
				)
			)
		)
		(sheetname "USER_IO")
		(sheetfile "USER_IO.kicad_sch")
		(duplicate_pad_numbers_are_jumpers no)
		(pad "1" smd rect
			(at -0.75 0)
			(size 0.95 0.95)
			(layers "F.Cu" "F.Mask" "F.Paste")
			(net "ANT1_IO_IN")
		)
		(pad "2" smd rect
			(at 0.75 0)
			(size 0.95 0.95)
			(layers "F.Cu" "F.Mask" "F.Paste")
			(net "+3.3V")
		)
	)
	(footprint "Vault:RESC3116X65X50ML20T20"
		(layer "F.Cu")
		(at 214.3261 97.7162 180)
		(property "Reference" "R44"
			(at -1.9714 -1.673069 180)
			(unlocked yes)
			(layer "F.SilkS")
			(effects
				(font
					(size 0.762 0.762)
					(thickness 0.2286)
				)
			)
		)
		(property "Value" "DNI_0_5%_1206"
			(at 7.27402 3.291071 180)
			(unlocked yes)
			(layer "F.SilkS")
			(hide yes)
			(effects
				(font
					(size 0.762 0.762)
					(thickness 0.2286)
				)
			)
		)
		(sheetname "POWER")
		(sheetfile "POWER.kicad_sch")
		(duplicate_pad_numbers_are_jumpers no)
		(fp_line
			(start 0.35 0.85)
			(end -0.35 0.85)
			(stroke
				(width 0.2)
				(type solid)
			)
			(layer "F.SilkS")
		)
		(fp_line
			(start 0.35 -0.85)
			(end -0.35 -0.85)
			(stroke
				(width 0.2)
				(type solid)
			)
			(layer "F.SilkS")
		)
		(pad "1" smd rect
			(at -1.475 0 270)
			(size 1.9 1.45)
			(layers "F.Cu" "F.Mask" "F.Paste")
			(net "NetD12_1")
		)
		(pad "2" smd rect
			(at 1.475 0 270)
			(size 1.9 1.45)
			(layers "F.Cu" "F.Mask" "F.Paste")
			(net "+12V_SENS")
		)
	)
	(footprint "Vault:RESC1005X40X25LL05T05"
		(layer "F.Cu")
		(at 206.4261 82.9162)
		(property "Reference" "R64"
			(at 0.2286 -1.173069 0)
			(unlocked yes)
			(layer "F.SilkS")
			(effects
				(font
					(size 0.762 0.762)
					(thickness 0.2286)
				)
			)
		)
		(property "Value" "0_1%_0402"
			(at -2.579871 6.66536 270)
			(unlocked yes)
			(layer "F.SilkS")
			(hide yes)
			(effects
				(font
					(size 0.762 0.762)
					(thickness 0.2286)
				)
			)
		)
		(sheetname "POWER")
		(sheetfile "POWER.kicad_sch")
		(duplicate_pad_numbers_are_jumpers no)
		(pad "1" smd rect
			(at -0.4 0 90)
			(size 0.45 0.45)
			(layers "F.Cu" "F.Mask" "F.Paste")
			(net "NetR64_1")
		)
		(pad "2" smd rect
			(at 0.4 0 90)
			(size 0.45 0.45)
			(layers "F.Cu" "F.Mask" "F.Paste")
			(net "GND")
		)
	)
	(footprint "Vault:RESC1005X40X25LL10T10"
		(layer "F.Cu")
		(at 214.0261 127.2162 90)
		(property "Reference" "R73"
			(at 1.9714 -0.226931 270)
			(unlocked yes)
			(layer "F.SilkS")
			(effects
				(font
					(size 0.762 0.762)
					(thickness 0.2286)
				)
			)
		)
		(property "Value" "1.21_1%_0402"
			(at -2.579871 8.569745 0)
			(unlocked yes)
			(layer "F.SilkS")
			(hide yes)
			(effects
				(font
					(size 0.762 0.762)
					(thickness 0.2286)
				)
			)
		)
		(sheetname "POWER")
		(sheetfile "POWER.kicad_sch")
		(duplicate_pad_numbers_are_jumpers no)
		(pad "1" smd rect
			(at -0.375 0 180)
			(size 0.5 0.55)
			(layers "F.Cu" "F.Mask" "F.Paste")
			(net "NetC72_1")
		)
		(pad "2" smd rect
			(at 0.375 0 180)
			(size 0.5 0.55)
			(layers "F.Cu" "F.Mask" "F.Paste")
			(net "NetL2_1")
		)
	)
	(footprint "Vault:RESC1608X55X30NL15T15"
		(layer "F.Cu")
		(at 83.3761 89.6162)
		(property "Reference" "R41"
			(at -2.521405 0.026921 0)
			(unlocked yes)
			(layer "F.SilkS")
			(effects
				(font
					(size 0.762 0.762)
					(thickness 0.2286)
				)
			)
		)
		(property "Value" "4.7K"
			(at 1.61204 2.325871 0)
			(unlocked yes)
			(layer "F.SilkS")
			(hide yes)
			(effects
				(font
					(size 0.762 0.762)
					(thickness 0.2286)
				)
			)
		)
		(sheetname "USER_IO_STATUS")
		(sheetfile "USER_IO_STATUS.kicad_sch")
		(duplicate_pad_numbers_are_jumpers no)
		(pad "1" smd rect
			(at -0.75 0 90)
			(size 0.95 0.95)
			(layers "F.Cu" "F.Mask" "F.Paste")
			(net "GND")
		)
		(pad "2" smd rect
			(at 0.75 0 90)
			(size 0.95 0.95)
			(layers "F.Cu" "F.Mask" "F.Paste")
			(net "NetR41_2")
		)
	)
	(footprint "Vault:SOT143-4L"
		(layer "F.Cu")
		(at 71.8761 100.7662 90)
		(property "Reference" "D1"
			(at -2.776921 1.478595 0)
			(unlocked yes)
			(layer "F.SilkS")
			(effects
				(font
					(size 0.762 0.762)
					(thickness 0.2286)
				)
			)
		)
		(property "Value" "8240136"
			(at 2.6781 3.341871 90)
			(unlocked yes)
			(layer "F.SilkS")
			(hide yes)
			(effects
				(font
					(size 0.762 0.762)
					(thickness 0.2286)
				)
			)
		)
		(sheetname "USER_IO")
		(sheetfile "USER_IO.kicad_sch")
		(duplicate_pad_numbers_are_jumpers no)
		(fp_line
			(start 2.05 -1.7)
			(end 2.05 1.7)
			(stroke
				(width 0.2)
				(type solid)
			)
			(layer "F.SilkS")
		)
		(fp_line
			(start -2.05 -1.7)
			(end 2.05 -1.7)
			(stroke
				(width 0.2)
				(type solid)
			)
			(layer "F.SilkS")
		)
		(fp_line
			(start -2.05 -1.7)
			(end -2.05 1.675)
			(stroke
				(width 0.2)
				(type solid)
			)
			(layer "F.SilkS")
		)
		(fp_line
			(start -2.05 1.7)
			(end 2.05 1.7)
			(stroke
				(width 0.2)
				(type solid)
			)
			(layer "F.SilkS")
		)
		(fp_circle
			(center -2.404 -1.075)
			(end -2.15 -1.075)
			(stroke
				(width 0.2)
				(type solid)
			)
			(fill no)
			(layer "F.SilkS")
		)
		(pad "1" smd rect
			(at -1.1 -0.75 180)
			(size 1.4 1.4)
			(layers "F.Cu" "F.Mask" "F.Paste")
			(net "GND")
		)
		(pad "2" smd rect
			(at -1.1 0.95 180)
			(size 1 1.4)
			(layers "F.Cu" "F.Mask" "F.Paste")
			(net "NetAN2_1")
		)
		(pad "3" smd rect
			(at 1.1 0.95 180)
			(size 1 1.4)
			(layers "F.Cu" "F.Mask" "F.Paste")
			(net "NetAN1_1")
		)
		(pad "4" smd rect
			(at 1.1 -0.95 180)
			(size 1 1.4)
			(layers "F.Cu" "F.Mask" "F.Paste")
			(net "+3.3V")
		)
	)
)
